(kicad_pcb
	(version 20260206)
	(generator "pcbnew")
	(generator_version "10.0")
	(general
		(thickness 1.6)
		(legacy_teardrops no)
	)
	(paper "A4")
	(title_block
		(title "12092022_DA0F0TMDCD0_F0T_Management_Board_D_brd_V3_OCP.brd")
		(comment 1 "Grand Teton / footprints 263-267 of 1440")
	)
	(layers
		(0 "F.Cu" signal "TOP")
		(4 "In1.Cu" signal "GND")
		(6 "In2.Cu" signal "IN1")
		(8 "In3.Cu" signal "GND1")
		(10 "In4.Cu" signal "IN2")
		(12 "In5.Cu" signal "VCC")
		(14 "In6.Cu" signal "VCC1")
		(16 "In7.Cu" signal "IN3")
		(18 "In8.Cu" signal "GND2")
		(20 "In9.Cu" signal "IN4")
		(22 "In10.Cu" signal "GND3")
		(2 "B.Cu" signal "BOTTOM")
		(9 "F.Adhes" user "F.Adhesive")
		(11 "B.Adhes" user "B.Adhesive")
		(13 "F.Paste" user "Package Geometry/Pastemask Top")
		(15 "B.Paste" user "Package Geometry/Pastemask Bottom")
		(5 "F.SilkS" user "Ref Des/Silkscreen Top")
		(7 "B.SilkS" user "Ref Des/Silkscreen Bottom")
		(1 "F.Mask" user "Board Geometry/Soldermask Top")
		(3 "B.Mask" user "Board Geometry/Soldermask Bottom")
		(17 "Dwgs.User" user "User.Drawings")
		(19 "Cmts.User" user "User.Comments")
		(21 "Eco1.User" user "User.Eco1")
		(23 "Eco2.User" user "User.Eco2")
		(25 "Edge.Cuts" user "Board Geometry/Outline")
		(27 "Margin" user)
		(31 "F.CrtYd" user "Package Geometry/Place Bound Top")
		(29 "B.CrtYd" user "Package Geometry/Place Bound Bottom")
		(35 "F.Fab" user "Ref Des/Assembly Top")
		(33 "B.Fab" user "Ref Des/Assembly Bottom")
	)
	(footprint ""
		(layer "F.Cu")
		(at 40.0558 -42.4434)
		(property "Reference" "R443"
			(at 0 0 0)
			(layer "F.SilkS")
			(hide yes)
			(effects
				(font
					(size 1.27 1.27)
				)
			)
		)
		(property "Value" ""
			(at 0 0 0)
			(layer "F.Fab")
			(effects
				(font
					(size 1.27 1.27)
				)
			)
		)
		(duplicate_pad_numbers_are_jumpers no)
		(fp_line
			(start -0.7874 -0.4064)
			(end 0.7874 -0.4064)
			(stroke
				(width 0.1524)
				(type default)
			)
			(layer "F.SilkS")
		)
		(fp_line
			(start -0.7874 0.4064)
			(end -0.7874 -0.4064)
			(stroke
				(width 0.1524)
				(type default)
			)
			(layer "F.SilkS")
		)
		(fp_line
			(start 0.7874 -0.4064)
			(end 0.7874 0.4064)
			(stroke
				(width 0.1524)
				(type default)
			)
			(layer "F.SilkS")
		)
		(fp_line
			(start 0.7874 0.4064)
			(end -0.7874 0.4064)
			(stroke
				(width 0.1524)
				(type default)
			)
			(layer "F.SilkS")
		)
		(fp_line
			(start -0.67945 -0.305054)
			(end -0.12065 -0.305054)
			(stroke
				(width 0.1)
				(type default)
			)
			(layer "F.Fab")
		)
		(fp_line
			(start -0.67945 0.3048)
			(end -0.67945 -0.305054)
			(stroke
				(width 0.1)
				(type default)
			)
			(layer "F.Fab")
		)
		(fp_line
			(start -0.12065 -0.305054)
			(end -0.12065 -0.2794)
			(stroke
				(width 0.1)
				(type default)
			)
			(layer "F.Fab")
		)
		(fp_line
			(start -0.12065 -0.2794)
			(end 0.12065 -0.2794)
			(stroke
				(width 0.1)
				(type default)
			)
			(layer "F.Fab")
		)
		(fp_line
			(start -0.12065 0.2794)
			(end -0.12065 0.3048)
			(stroke
				(width 0.1)
				(type default)
			)
			(layer "F.Fab")
		)
		(fp_line
			(start -0.12065 0.3048)
			(end -0.67945 0.3048)
			(stroke
				(width 0.1)
				(type default)
			)
			(layer "F.Fab")
		)
		(fp_line
			(start 0.120396 0.2794)
			(end -0.12065 0.2794)
			(stroke
				(width 0.1)
				(type default)
			)
			(layer "F.Fab")
		)
		(fp_line
			(start 0.120396 0.3048)
			(end 0.120396 0.2794)
			(stroke
				(width 0.1)
				(type default)
			)
			(layer "F.Fab")
		)
		(fp_line
			(start 0.12065 -0.3048)
			(end 0.67945 -0.3048)
			(stroke
				(width 0.1)
				(type default)
			)
			(layer "F.Fab")
		)
		(fp_line
			(start 0.12065 -0.2794)
			(end 0.12065 -0.3048)
			(stroke
				(width 0.1)
				(type default)
			)
			(layer "F.Fab")
		)
		(fp_line
			(start 0.67945 -0.3048)
			(end 0.67945 0.3048)
			(stroke
				(width 0.1)
				(type default)
			)
			(layer "F.Fab")
		)
		(fp_line
			(start 0.67945 0.3048)
			(end 0.120396 0.3048)
			(stroke
				(width 0.1)
				(type default)
			)
			(layer "F.Fab")
		)
		(pad "1" smd circle
			(at -0.40005 0)
			(size 0 0)
			(layers "F.Cu" "F.Mask" "F.Paste")
			(net "SMB_BMC_ALERT4_N")
		)
		(pad "2" smd circle
			(at 0.40005 0)
			(size 0 0)
			(layers "F.Cu" "F.Mask" "F.Paste")
			(net "SMB_BMC_ALERT4_R_N")
		)
	)
	(footprint ""
		(layer "F.Cu")
		(at 37.865304 -47.587916)
		(property "Reference" "R145"
			(at 0 0 0)
			(layer "F.SilkS")
			(hide yes)
			(effects
				(font
					(size 1.27 1.27)
				)
			)
		)
		(property "Value" ""
			(at 0 0 0)
			(layer "F.Fab")
			(effects
				(font
					(size 1.27 1.27)
				)
			)
		)
		(duplicate_pad_numbers_are_jumpers no)
		(fp_line
			(start -0.7874 -0.4064)
			(end 0.7874 -0.4064)
			(stroke
				(width 0.1524)
				(type default)
			)
			(layer "F.SilkS")
		)
		(fp_line
			(start -0.7874 0.4064)
			(end -0.7874 -0.4064)
			(stroke
				(width 0.1524)
				(type default)
			)
			(layer "F.SilkS")
		)
		(fp_line
			(start 0.7874 -0.4064)
			(end 0.7874 0.4064)
			(stroke
				(width 0.1524)
				(type default)
			)
			(layer "F.SilkS")
		)
		(fp_line
			(start 0.7874 0.4064)
			(end -0.7874 0.4064)
			(stroke
				(width 0.1524)
				(type default)
			)
			(layer "F.SilkS")
		)
		(fp_line
			(start -0.67945 -0.305054)
			(end -0.12065 -0.305054)
			(stroke
				(width 0.1)
				(type default)
			)
			(layer "F.Fab")
		)
		(fp_line
			(start -0.67945 0.3048)
			(end -0.67945 -0.305054)
			(stroke
				(width 0.1)
				(type default)
			)
			(layer "F.Fab")
		)
		(fp_line
			(start -0.12065 -0.305054)
			(end -0.12065 -0.2794)
			(stroke
				(width 0.1)
				(type default)
			)
			(layer "F.Fab")
		)
		(fp_line
			(start -0.12065 -0.2794)
			(end 0.12065 -0.2794)
			(stroke
				(width 0.1)
				(type default)
			)
			(layer "F.Fab")
		)
		(fp_line
			(start -0.12065 0.2794)
			(end -0.12065 0.3048)
			(stroke
				(width 0.1)
				(type default)
			)
			(layer "F.Fab")
		)
		(fp_line
			(start -0.12065 0.3048)
			(end -0.67945 0.3048)
			(stroke
				(width 0.1)
				(type default)
			)
			(layer "F.Fab")
		)
		(fp_line
			(start 0.120396 0.2794)
			(end -0.12065 0.2794)
			(stroke
				(width 0.1)
				(type default)
			)
			(layer "F.Fab")
		)
		(fp_line
			(start 0.120396 0.3048)
			(end 0.120396 0.2794)
			(stroke
				(width 0.1)
				(type default)
			)
			(layer "F.Fab")
		)
		(fp_line
			(start 0.12065 -0.3048)
			(end 0.67945 -0.3048)
			(stroke
				(width 0.1)
				(type default)
			)
			(layer "F.Fab")
		)
		(fp_line
			(start 0.12065 -0.2794)
			(end 0.12065 -0.3048)
			(stroke
				(width 0.1)
				(type default)
			)
			(layer "F.Fab")
		)
		(fp_line
			(start 0.67945 -0.3048)
			(end 0.67945 0.3048)
			(stroke
				(width 0.1)
				(type default)
			)
			(layer "F.Fab")
		)
		(fp_line
			(start 0.67945 0.3048)
			(end 0.120396 0.3048)
			(stroke
				(width 0.1)
				(type default)
			)
			(layer "F.Fab")
		)
		(pad "1" smd circle
			(at -0.40005 0)
			(size 0 0)
			(layers "F.Cu" "F.Mask" "F.Paste")
			(net "P3V3_AUX")
		)
		(pad "2" smd circle
			(at 0.40005 0)
			(size 0 0)
			(layers "F.Cu" "F.Mask" "F.Paste")
			(net "SMB_BMC_MM12_SCL")
		)
	)
	(footprint ""
		(layer "F.Cu")
		(at 95.904304 42.085514 90)
		(property "Reference" "J16"
			(at -1.094486 2.801366 90)
			(unlocked yes)
			(layer "F.SilkS")
			(effects
				(font
					(size 0.7874 0.5842)
					(thickness 0.1524)
				)
				(justify left)
			)
		)
		(property "Value" ""
			(at 0 0 90)
			(layer "F.Fab")
			(effects
				(font
					(size 1.27 1.27)
				)
			)
		)
		(duplicate_pad_numbers_are_jumpers no)
		(fp_line
			(start 1.2192 -2.1082)
			(end 1.2192 -0.801878)
			(stroke
				(width 0.1524)
				(type default)
			)
			(layer "F.SilkS")
		)
		(fp_line
			(start -1.2192 -2.1082)
			(end 1.2192 -2.1082)
			(stroke
				(width 0.1524)
				(type default)
			)
			(layer "F.SilkS")
		)
		(fp_line
			(start 1.2192 0.810768)
			(end 1.2192 2.1082)
			(stroke
				(width 0.1524)
				(type default)
			)
			(layer "F.SilkS")
		)
		(fp_line
			(start 1.2192 2.1082)
			(end -1.2192 2.1082)
			(stroke
				(width 0.1524)
				(type default)
			)
			(layer "F.SilkS")
		)
		(fp_line
			(start -1.2192 2.1082)
			(end -1.2192 -2.1082)
			(stroke
				(width 0.1524)
				(type default)
			)
			(layer "F.SilkS")
		)
		(pad "" np_thru_hole circle
			(at -2.8829 -1.27)
			(size 1.0414 1.0414)
			(drill 1.0414)
			(layers "*.Cu" "*.Mask")
			(clearance 0.381)
			(thermal_gap 0.381)
		)
		(pad "" np_thru_hole circle
			(at -2.8829 1.27)
			(size 1.0414 1.0414)
			(drill 1.0414)
			(layers "*.Cu" "*.Mask")
			(clearance 0.381)
			(thermal_gap 0.381)
		)
		(pad "" np_thru_hole circle
			(at 3.4671 -1.27)
			(size 1.0414 1.0414)
			(drill 1.0414)
			(layers "*.Cu" "*.Mask")
			(clearance 0.381)
			(thermal_gap 0.381)
		)
		(pad "" np_thru_hole circle
			(at 3.4671 1.27)
			(size 1.0414 1.0414)
			(drill 1.0414)
			(layers "*.Cu" "*.Mask")
			(clearance 0.381)
			(thermal_gap 0.381)
		)
		(pad "1" smd rect
			(at 0.8255 -0.249936)
			(size 0.3048 0.508)
			(layers "F.Cu" "F.Mask" "F.Paste")
			(net "85_5INCH_IN4_DN")
		)
		(pad "2" smd rect
			(at 0.8255 0.249936)
			(size 0.3048 0.508)
			(layers "F.Cu" "F.Mask" "F.Paste")
			(net "85_5INCH_IN4_DP")
		)
		(pad "3" smd circle
			(at 0 0 90)
			(size 0 0)
			(layers "F.Cu" "F.Mask" "F.Paste")
			(net "GND_P1")
		)
		(zone
			(layer "F.Cu")
			(hatch none 0.5)
			(connect_pads
				(clearance 0)
			)
			(min_thickness 0.25)
			(keepout
				(tracks not_allowed)
				(vias allowed)
				(pads allowed)
				(copperpour not_allowed)
				(footprints allowed)
			)
			(placement
				(enabled no)
				(sheetname "")
			)
			(fill
				(thermal_gap 0.5)
				(thermal_bridge_width 0.5)
				(island_removal_mode 0)
			)
			(polygon
				(pts
					(xy 95.355664 40.967914) (xy 95.451168 40.967914) (xy 95.451168 41.564814) (xy 95.857568 41.564814)
					(xy 95.857568 40.967914) (xy 95.95104 40.967914) (xy 95.95104 41.564814) (xy 96.35744 41.564814)
					(xy 96.35744 40.967914) (xy 96.452944 40.967914) (xy 96.452944 41.666414) (xy 95.355664 41.666414)
				)
			)
		)
		(zone
			(layers "F.Cu" "B.Cu" "In1.Cu" "In2.Cu" "In3.Cu" "In4.Cu" "In5.Cu" "In6.Cu"
				"In7.Cu" "In8.Cu" "In9.Cu" "In10.Cu"
			)
			(hatch none 0.5)
			(connect_pads
				(clearance 0)
			)
			(min_thickness 0.25)
			(keepout
				(tracks not_allowed)
				(vias allowed)
				(pads allowed)
				(copperpour not_allowed)
				(footprints allowed)
			)
			(placement
				(enabled no)
				(sheetname "")
			)
			(fill
				(thermal_gap 0.5)
				(thermal_bridge_width 0.5)
				(island_removal_mode 0)
			)
			(polygon
				(pts
					(arc
						(start 95.561404 38.618414)
						(mid 93.707204 38.618414)
						(end 95.561404 38.618414)
					)
				)
			)
		)
		(zone
			(layers "F.Cu" "B.Cu" "In1.Cu" "In2.Cu" "In3.Cu" "In4.Cu" "In5.Cu" "In6.Cu"
				"In7.Cu" "In8.Cu" "In9.Cu" "In10.Cu"
			)
			(hatch none 0.5)
			(connect_pads
				(clearance 0)
			)
			(min_thickness 0.25)
			(keepout
				(tracks not_allowed)
				(vias allowed)
				(pads allowed)
				(copperpour not_allowed)
				(footprints allowed)
			)
			(placement
				(enabled no)
				(sheetname "")
			)
			(fill
				(thermal_gap 0.5)
				(thermal_bridge_width 0.5)
				(island_removal_mode 0)
			)
			(polygon
				(pts
					(arc
						(start 95.561404 44.968414)
						(mid 93.707204 44.968414)
						(end 95.561404 44.968414)
					)
				)
			)
		)
		(zone
			(layers "F.Cu" "B.Cu" "In1.Cu" "In2.Cu" "In3.Cu" "In4.Cu" "In5.Cu" "In6.Cu"
				"In7.Cu" "In8.Cu" "In9.Cu" "In10.Cu"
			)
			(hatch none 0.5)
			(connect_pads
				(clearance 0)
			)
			(min_thickness 0.25)
			(keepout
				(tracks not_allowed)
				(vias allowed)
				(pads allowed)
				(copperpour not_allowed)
				(footprints allowed)
			)
			(placement
				(enabled no)
				(sheetname "")
			)
			(fill
				(thermal_gap 0.5)
				(thermal_bridge_width 0.5)
				(island_removal_mode 0)
			)
			(polygon
				(pts
					(arc
						(start 98.101404 38.618414)
						(mid 96.247204 38.618414)
						(end 98.101404 38.618414)
					)
				)
			)
		)
		(zone
			(layers "F.Cu" "B.Cu" "In1.Cu" "In2.Cu" "In3.Cu" "In4.Cu" "In5.Cu" "In6.Cu"
				"In7.Cu" "In8.Cu" "In9.Cu" "In10.Cu"
			)
			(hatch none 0.5)
			(connect_pads
				(clearance 0)
			)
			(min_thickness 0.25)
			(keepout
				(tracks not_allowed)
				(vias allowed)
				(pads allowed)
				(copperpour not_allowed)
				(footprints allowed)
			)
			(placement
				(enabled no)
				(sheetname "")
			)
			(fill
				(thermal_gap 0.5)
				(thermal_bridge_width 0.5)
				(island_removal_mode 0)
			)
			(polygon
				(pts
					(arc
						(start 98.101404 44.968414)
						(mid 96.247204 44.968414)
						(end 98.101404 44.968414)
					)
				)
			)
		)
	)
	(footprint ""
		(layer "F.Cu")
		(at 13.335 -109.347 90)
		(property "Reference" "C271"
			(at 0 0 90)
			(layer "F.SilkS")
			(hide yes)
			(effects
				(font
					(size 1.27 1.27)
				)
			)
		)
		(property "Value" ""
			(at 0 0 90)
			(layer "F.Fab")
			(effects
				(font
					(size 1.27 1.27)
				)
			)
		)
		(duplicate_pad_numbers_are_jumpers no)
		(fp_line
			(start 0.7874 -0.4064)
			(end 0.7874 -0.1016)
			(stroke
				(width 0.1524)
				(type default)
			)
			(layer "F.SilkS")
		)
		(fp_line
			(start -0.7874 -0.4064)
			(end 0.7874 -0.4064)
			(stroke
				(width 0.1524)
				(type default)
			)
			(layer "F.SilkS")
		)
		(fp_line
			(start -0.7874 -0.0254)
			(end -0.7874 -0.4064)
			(stroke
				(width 0.1524)
				(type default)
			)
			(layer "F.SilkS")
		)
		(fp_line
			(start 0.4064 0.4064)
			(end -0.4318 0.4064)
			(stroke
				(width 0.1524)
				(type default)
			)
			(layer "F.SilkS")
		)
		(fp_line
			(start -0.12065 -0.305054)
			(end -0.12065 -0.2794)
			(stroke
				(width 0.1)
				(type default)
			)
			(layer "F.Fab")
		)
		(fp_line
			(start -0.67945 -0.305054)
			(end -0.12065 -0.305054)
			(stroke
				(width 0.1)
				(type default)
			)
			(layer "F.Fab")
		)
		(fp_line
			(start 0.67945 -0.3048)
			(end 0.67945 0.3048)
			(stroke
				(width 0.1)
				(type default)
			)
			(layer "F.Fab")
		)
		(fp_line
			(start 0.12065 -0.3048)
			(end 0.67945 -0.3048)
			(stroke
				(width 0.1)
				(type default)
			)
			(layer "F.Fab")
		)
		(fp_line
			(start 0.12065 -0.2794)
			(end 0.12065 -0.3048)
			(stroke
				(width 0.1)
				(type default)
			)
			(layer "F.Fab")
		)
		(fp_line
			(start -0.12065 -0.2794)
			(end 0.12065 -0.2794)
			(stroke
				(width 0.1)
				(type default)
			)
			(layer "F.Fab")
		)
		(fp_line
			(start 0.120396 0.2794)
			(end -0.12065 0.2794)
			(stroke
				(width 0.1)
				(type default)
			)
			(layer "F.Fab")
		)
		(fp_line
			(start -0.12065 0.2794)
			(end -0.12065 0.3048)
			(stroke
				(width 0.1)
				(type default)
			)
			(layer "F.Fab")
		)
		(fp_line
			(start 0.67945 0.3048)
			(end 0.120396 0.3048)
			(stroke
				(width 0.1)
				(type default)
			)
			(layer "F.Fab")
		)
		(fp_line
			(start 0.120396 0.3048)
			(end 0.120396 0.2794)
			(stroke
				(width 0.1)
				(type default)
			)
			(layer "F.Fab")
		)
		(fp_line
			(start -0.12065 0.3048)
			(end -0.67945 0.3048)
			(stroke
				(width 0.1)
				(type default)
			)
			(layer "F.Fab")
		)
		(fp_line
			(start -0.67945 0.3048)
			(end -0.67945 -0.305054)
			(stroke
				(width 0.1)
				(type default)
			)
			(layer "F.Fab")
		)
		(pad "1" smd circle
			(at -0.40005 0 90)
			(size 0 0)
			(layers "F.Cu" "F.Mask" "F.Paste")
			(net "P2E_GPU_TX_DN")
		)
		(pad "2" smd circle
			(at 0.40005 0 90)
			(size 0 0)
			(layers "F.Cu" "F.Mask" "F.Paste")
			(net "P2E_GPU_TX_C_DN")
		)
	)
	(footprint ""
		(layer "F.Cu")
		(at 16.0782 -65.8622 90)
		(property "Reference" "C501"
			(at 0 0 90)
			(layer "F.SilkS")
			(hide yes)
			(effects
				(font
					(size 1.27 1.27)
				)
			)
		)
		(property "Value" ""
			(at 0 0 90)
			(layer "F.Fab")
			(effects
				(font
					(size 1.27 1.27)
				)
			)
		)
		(duplicate_pad_numbers_are_jumpers no)
		(fp_line
			(start 0.7874 -0.4064)
			(end 0.7874 0.4064)
			(stroke
				(width 0.1524)
				(type default)
			)
			(layer "F.SilkS")
		)
		(fp_line
			(start -0.7874 -0.4064)
			(end 0.7874 -0.4064)
			(stroke
				(width 0.1524)
				(type default)
			)
			(layer "F.SilkS")
		)
		(fp_line
			(start 0.7874 0.4064)
			(end -0.7874 0.4064)
			(stroke
				(width 0.1524)
				(type default)
			)
			(layer "F.SilkS")
		)
		(fp_line
			(start -0.7874 0.4064)
			(end -0.7874 -0.4064)
			(stroke
				(width 0.1524)
				(type default)
			)
			(layer "F.SilkS")
		)
		(fp_line
			(start -0.12065 -0.305054)
			(end -0.12065 -0.2794)
			(stroke
				(width 0.1)
				(type default)
			)
			(layer "F.Fab")
		)
		(fp_line
			(start -0.67945 -0.305054)
			(end -0.12065 -0.305054)
			(stroke
				(width 0.1)
				(type default)
			)
			(layer "F.Fab")
		)
		(fp_line
			(start 0.67945 -0.3048)
			(end 0.67945 0.3048)
			(stroke
				(width 0.1)
				(type default)
			)
			(layer "F.Fab")
		)
		(fp_line
			(start 0.12065 -0.3048)
			(end 0.67945 -0.3048)
			(stroke
				(width 0.1)
				(type default)
			)
			(layer "F.Fab")
		)
		(fp_line
			(start 0.12065 -0.2794)
			(end 0.12065 -0.3048)
			(stroke
				(width 0.1)
				(type default)
			)
			(layer "F.Fab")
		)
		(fp_line
			(start -0.12065 -0.2794)
			(end 0.12065 -0.2794)
			(stroke
				(width 0.1)
				(type default)
			)
			(layer "F.Fab")
		)
		(fp_line
			(start 0.120396 0.2794)
			(end -0.12065 0.2794)
			(stroke
				(width 0.1)
				(type default)
			)
			(layer "F.Fab")
		)
		(fp_line
			(start -0.12065 0.2794)
			(end -0.12065 0.3048)
			(stroke
				(width 0.1)
				(type default)
			)
			(layer "F.Fab")
		)
		(fp_line
			(start 0.67945 0.3048)
			(end 0.120396 0.3048)
			(stroke
				(width 0.1)
				(type default)
			)
			(layer "F.Fab")
		)
		(fp_line
			(start 0.120396 0.3048)
			(end 0.120396 0.2794)
			(stroke
				(width 0.1)
				(type default)
			)
			(layer "F.Fab")
		)
		(fp_line
			(start -0.12065 0.3048)
			(end -0.67945 0.3048)
			(stroke
				(width 0.1)
				(type default)
			)
			(layer "F.Fab")
		)
		(fp_line
			(start -0.67945 0.3048)
			(end -0.67945 -0.305054)
			(stroke
				(width 0.1)
				(type default)
			)
			(layer "F.Fab")
		)
		(pad "1" smd circle
			(at -0.40005 0 90)
			(size 0 0)
			(layers "F.Cu" "F.Mask" "F.Paste")
			(net "P3V3_AUX")
		)
		(pad "2" smd circle
			(at 0.40005 0 90)
			(size 0 0)
			(layers "F.Cu" "F.Mask" "F.Paste")
			(net "GND")
		)
	)
)
